FILE_TYPE = MACRO_DRAWING;
SET COLOR_WIRE YELLOW;
SET COLOR_PROP MONO;
SET COLOR_DOT WHITE;
SET COLOR_ARC YELLOW;
SET COLOR_BODY GREEN;
SET COLOR_NOTE MONO;
SET PROP_DISPLAY VALUE;
SET PAGE_NUMBER P91;
FORCEADD SCONN24_H46321001..1
(-125 2850);
FORCEPROP 1 LAST LOCATION J8B1
J 0
(-475 3400);
DISPLAY 0.617021 (-475 3400);
PAINT AQUA (-475 3400);
FORCEPROP 1 LAST PART_NUMBER H46321-001
J 0
(-475 2350);
DISPLAY 0.617021 (-475 2350);
PAINT BLUE (-475 2350);
FORCEPROP 1 LAST MATERIAL SCONN
J 0
(-475 3350);
DISPLAY 0.617021 (-475 3350);
PAINT SKYBLUE (-475 3350);
FORCEPROP 2 LASTPIN (-525 2500) $PN MP1
J 2
(-510 2510);
DISPLAY 0.617021 (-510 2510);
PAINT MONO (-510 2510);
FORCEPROP 2 LASTPIN (275 2600) $PN 24
J 0
(285 2610);
DISPLAY 0.617021 (285 2610);
PAINT MONO (285 2610);
FORCEPROP 2 LASTPIN (-525 2600) $PN 23
J 2
(-535 2610);
DISPLAY 0.617021 (-535 2610);
PAINT MONO (-535 2610);
FORCEPROP 2 LASTPIN (275 2650) $PN 22
J 0
(285 2660);
DISPLAY 0.617021 (285 2660);
PAINT MONO (285 2660);
FORCEPROP 2 LASTPIN (-525 2650) $PN 21
J 2
(-535 2660);
DISPLAY 0.617021 (-535 2660);
PAINT MONO (-535 2660);
FORCEPROP 2 LASTPIN (275 2700) $PN 20
J 0
(285 2710);
DISPLAY 0.617021 (285 2710);
PAINT MONO (285 2710);
FORCEPROP 2 LASTPIN (-525 2700) $PN 19
J 2
(-535 2710);
DISPLAY 0.617021 (-535 2710);
PAINT MONO (-535 2710);
FORCEPROP 2 LASTPIN (275 2750) $PN 18
J 0
(285 2760);
DISPLAY 0.617021 (285 2760);
PAINT MONO (285 2760);
FORCEPROP 2 LASTPIN (-525 2750) $PN 17
J 2
(-535 2760);
DISPLAY 0.617021 (-535 2760);
PAINT MONO (-535 2760);
FORCEPROP 2 LASTPIN (275 2800) $PN 16
J 0
(285 2810);
DISPLAY 0.617021 (285 2810);
PAINT MONO (285 2810);
FORCEPROP 2 LASTPIN (-525 2800) $PN 15
J 2
(-535 2810);
DISPLAY 0.617021 (-535 2810);
PAINT MONO (-535 2810);
FORCEPROP 2 LASTPIN (275 2850) $PN 14
J 0
(285 2860);
DISPLAY 0.617021 (285 2860);
PAINT MONO (285 2860);
FORCEPROP 2 LASTPIN (-525 2850) $PN 13
J 2
(-535 2860);
DISPLAY 0.617021 (-535 2860);
PAINT MONO (-535 2860);
FORCEPROP 2 LASTPIN (275 2900) $PN 12
J 0
(285 2910);
DISPLAY 0.617021 (285 2910);
PAINT MONO (285 2910);
FORCEPROP 2 LASTPIN (-525 2900) $PN 11
J 2
(-535 2910);
DISPLAY 0.617021 (-535 2910);
PAINT MONO (-535 2910);
FORCEPROP 2 LASTPIN (275 2950) $PN 10
J 0
(285 2960);
DISPLAY 0.617021 (285 2960);
PAINT MONO (285 2960);
FORCEPROP 2 LASTPIN (-525 2950) $PN 9
J 2
(-535 2960);
DISPLAY 0.617021 (-535 2960);
PAINT MONO (-535 2960);
FORCEPROP 2 LASTPIN (275 3000) $PN 8
J 0
(285 3010);
DISPLAY 0.617021 (285 3010);
PAINT MONO (285 3010);
FORCEPROP 2 LASTPIN (-525 3000) $PN 7
J 2
(-535 3010);
DISPLAY 0.617021 (-535 3010);
PAINT MONO (-535 3010);
FORCEPROP 2 LASTPIN (275 3050) $PN 6
J 0
(285 3060);
DISPLAY 0.617021 (285 3060);
PAINT MONO (285 3060);
FORCEPROP 2 LASTPIN (-525 3050) $PN 5
J 2
(-535 3060);
DISPLAY 0.617021 (-535 3060);
PAINT MONO (-535 3060);
FORCEPROP 2 LASTPIN (275 3100) $PN 4
J 0
(285 3110);
DISPLAY 0.617021 (285 3110);
PAINT MONO (285 3110);
FORCEPROP 2 LASTPIN (-525 3100) $PN 3
J 2
(-535 3110);
DISPLAY 0.617021 (-535 3110);
PAINT MONO (-535 3110);
FORCEPROP 2 LASTPIN (275 3150) $PN 2
J 0
(285 3160);
DISPLAY 0.617021 (285 3160);
PAINT MONO (285 3160);
FORCEPROP 2 LASTPIN (-525 3150) $PN 1
J 2
(-535 3160);
DISPLAY 0.617021 (-535 3160);
PAINT MONO (-535 3160);
FORCEPROP 2 LASTPIN (275 2500) $PN MP2
J 0
(285 2510);
DISPLAY 0.617021 (285 2510);
PAINT MONO (285 2510);
FORCEPROP 1 LAST PACK_TYPE SM
J 0
(-475 3450);
DISPLAY 1.340426 (-475 3450);
PAINT SKYBLUE (-475 3450);
DISPLAY INVISIBLE (-475 3450);
FORCEPROP 2 LAST CDS_LIB mstr_sconn
J 0
(-125 2850);
PAINT ORANGE (-125 2850);
DISPLAY INVISIBLE (-125 2850);
FORCEPROP 2 LAST CDS_SEC 1
J 0
(-475 3450);
PAINT MONO (-475 3450);
DISPLAY INVISIBLE (-475 3450);
FORCEPROP 2 LAST $SEC 1
J 0
(-475 3450);
PAINT MONO (-475 3450);
DISPLAY INVISIBLE (-475 3450);
FORCEPROP 2 LAST CDS_LOCATION J8B1
J 0
(-475 3400);
DISPLAY 0.617021 (-475 3400);
PAINT AQUA (-475 3400);
DISPLAY INVISIBLE (-475 3400);
FORCEPROP 1 LAST PATH I1
J 0
(-125 3350);
PAINT GREEN (-125 3350);
DISPLAY INVISIBLE (-125 3350);
FORCEPROP 0 LAST ROOM HFI
J 0
(-475 3500);
DISPLAY 1.021277 (-475 3500);
PAINT ORANGE (-475 3500);
DISPLAY INVISIBLE (-475 3500);
FORCEADD OFFPAGE..4
(3100 2950);
FORCEPROP 2 LAST $XR0 29 
J 0
(3286 2950);
DISPLAY 0.638298 (3286 2950);
PAINT MONO (3286 2950);
FORCEPROP 2 LAST CDS_LIB mstr_standard
J 0
(3100 2950);
DISPLAY 1.340426 (3100 2950);
PAINT MONO (3100 2950);
DISPLAY INVISIBLE (3100 2950);
FORCEPROP 2 LAST PATH I10
J 0
(3425 3000);
DISPLAY 1.021277 (3425 3000);
PAINT ORANGE (3425 3000);
DISPLAY INVISIBLE (3425 3000);
FORCEPROP 1 LAST OFFPAGE TRUE
J 0
(3425 2825);
DISPLAY 1.170213 (3425 2825);
PAINT GREEN (3425 2825);
DISPLAY INVISIBLE (3425 2825);
FORCEPROP 1 LAST COMMENT_BODY TRUE
J 0
(3075 2850);
DISPLAY 1.170213 (3075 2850);
PAINT GREEN (3075 2850);
DISPLAY INVISIBLE (3075 2850);
FORCEADD OFFPAGE..4
(3100 2650);
FORCEPROP 2 LAST $XR3 188 
J 0
(3646 2650);
DISPLAY 0.638298 (3646 2650);
PAINT MONO (3646 2650);
FORCEPROP 2 LAST $XR2 186 
J 0
(3526 2650);
DISPLAY 0.638298 (3526 2650);
PAINT MONO (3526 2650);
FORCEPROP 2 LAST $XR1 159 
J 0
(3406 2650);
DISPLAY 0.638298 (3406 2650);
PAINT MONO (3406 2650);
FORCEPROP 2 LAST $XR0 138 
J 0
(3286 2650);
DISPLAY 0.638298 (3286 2650);
PAINT MONO (3286 2650);
FORCEPROP 2 LAST PATH I11
J 0
(3450 2750);
DISPLAY 1.021277 (3450 2750);
PAINT ORANGE (3450 2750);
DISPLAY INVISIBLE (3450 2750);
FORCEPROP 2 LAST CDS_LIB mstr_standard
J 0
(3100 2650);
DISPLAY 1.340426 (3100 2650);
PAINT MONO (3100 2650);
DISPLAY INVISIBLE (3100 2650);
FORCEPROP 1 LAST OFFPAGE TRUE
J 0
(3425 2525);
DISPLAY 1.170213 (3425 2525);
PAINT GREEN (3425 2525);
DISPLAY INVISIBLE (3425 2525);
FORCEPROP 1 LAST COMMENT_BODY TRUE
J 0
(3075 2550);
DISPLAY 1.170213 (3075 2550);
PAINT GREEN (3075 2550);
DISPLAY INVISIBLE (3075 2550);
FORCEADD OFFPAGE..3
(3100 2600);
FORCEPROP 2 LAST $XR3 188 
J 0
(3674 2600);
DISPLAY 0.638298 (3674 2600);
PAINT MONO (3674 2600);
FORCEPROP 2 LAST $XR2 186 
J 0
(3554 2600);
DISPLAY 0.638298 (3554 2600);
PAINT MONO (3554 2600);
FORCEPROP 2 LAST $XR1 159 
J 0
(3434 2600);
DISPLAY 0.638298 (3434 2600);
PAINT MONO (3434 2600);
FORCEPROP 2 LAST $XR0 138 
J 0
(3314 2600);
DISPLAY 0.638298 (3314 2600);
PAINT MONO (3314 2600);
FORCEPROP 2 LAST PATH I12
J 0
(4050 2650);
DISPLAY 1.021277 (4050 2650);
PAINT ORANGE (4050 2650);
DISPLAY INVISIBLE (4050 2650);
FORCEPROP 2 LAST CDS_LIB mstr_standard
J 0
(3100 2600);
DISPLAY 1.340426 (3100 2600);
PAINT MONO (3100 2600);
DISPLAY INVISIBLE (3100 2600);
FORCEPROP 1 LAST OFFPAGE TRUE
J 0
(3425 2475);
DISPLAY 1.170213 (3425 2475);
PAINT GREEN (3425 2475);
DISPLAY INVISIBLE (3425 2475);
FORCEPROP 1 LAST COMMENT_BODY TRUE
J 0
(3050 2500);
DISPLAY 1.170213 (3050 2500);
PAINT GREEN (3050 2500);
DISPLAY INVISIBLE (3050 2500);
FORCEADD RES..2
(1250 3375);
FORCEPROP 1 LAST LOCATION R8B8
J 0
(1295 3500);
DISPLAY 0.617021 (1295 3500);
PAINT AQUA (1295 3500);
FORCEPROP 1 LAST PART_NUMBER G21796-072
J 0
(1290 3250);
DISPLAY 0.617021 (1290 3250);
PAINT BLUE (1290 3250);
FORCEPROP 1 LAST VALUE 4.75K
J 0
(1295 3450);
DISPLAY 0.617021 (1295 3450);
PAINT SKYBLUE (1295 3450);
FORCEPROP 1 LAST PACK_TYPE 0402
J 0
(1290 3200);
DISPLAY 0.617021 (1290 3200);
PAINT SKYBLUE (1290 3200);
FORCEPROP 1 LAST WATTAGE 1/16W
J 0
(1290 3350);
DISPLAY 0.617021 (1290 3350);
PAINT SKYBLUE (1290 3350);
FORCEPROP 1 LASTPIN (1250 3275) $PN 2
J 0
(1255 3285);
DISPLAY 0.617021 (1255 3285);
PAINT WHITE (1255 3285);
FORCEPROP 1 LASTPIN (1250 3475) $PN 1
J 0
(1255 3437);
DISPLAY 0.617021 (1255 3437);
PAINT WHITE (1255 3437);
FORCEPROP 1 LAST MATERIAL CHIP
J 0
(1290 3300);
DISPLAY 0.617021 (1290 3300);
PAINT SKYBLUE (1290 3300);
FORCEPROP 1 LAST TOLERANCE 1%
J 0
(1295 3400);
DISPLAY 0.617021 (1295 3400);
PAINT SKYBLUE (1295 3400);
FORCEPROP 2 LAST CDS_LIB mstr_discrete
J 0
(1250 3375);
DISPLAY 0.829787 (1250 3375);
PAINT ORANGE (1250 3375);
DISPLAY INVISIBLE (1250 3375);
FORCEPROP 2 LAST SEC_TYPE 0402
J 0
(1300 3600);
DISPLAY 1.361702 (1300 3600);
PAINT ORANGE (1300 3600);
DISPLAY INVISIBLE (1300 3600);
FORCEPROP 2 LAST SIGNAL_MODEL DEFAULT_RESISTOR_4750OHM_2_1
J 0
(1300 3600);
PAINT MONO (1300 3600);
DISPLAY INVISIBLE (1300 3600);
FORCEPROP 2 LAST SEC 1
J 0
(1300 3600);
DISPLAY 0.914894 (1300 3600);
PAINT MONO (1300 3600);
DISPLAY INVISIBLE (1300 3600);
FORCEPROP 2 LAST CDS_LOCATION R8B8
J 0
(1295 3500);
DISPLAY 0.617021 (1295 3500);
PAINT AQUA (1295 3500);
DISPLAY INVISIBLE (1295 3500);
FORCEPROP 1 LAST PATH I14
J 0
(1300 3550);
DISPLAY 0.978723 (1300 3550);
PAINT WHITE (1300 3550);
DISPLAY INVISIBLE (1300 3550);
FORCEPROP 0 LAST ROOM HFI
J 0
(1300 3550);
DISPLAY 1.021277 (1300 3550);
PAINT ORANGE (1300 3550);
DISPLAY INVISIBLE (1300 3550);
FORCEADD RES..2
(1000 3375);
FORCEPROP 1 LAST LOCATION R8B10
J 0
(1045 3500);
DISPLAY 0.617021 (1045 3500);
PAINT AQUA (1045 3500);
FORCEPROP 1 LAST VALUE 4.75K
J 0
(1045 3450);
DISPLAY 0.617021 (1045 3450);
PAINT SKYBLUE (1045 3450);
FORCEPROP 1 LAST TOLERANCE 1%
J 0
(1045 3400);
DISPLAY 0.617021 (1045 3400);
PAINT SKYBLUE (1045 3400);
FORCEPROP 1 LAST PACK_TYPE 0402
J 0
(1040 3200);
DISPLAY 0.617021 (1040 3200);
PAINT SKYBLUE (1040 3200);
FORCEPROP 1 LASTPIN (1000 3275) $PN 2
J 0
(1005 3285);
DISPLAY 0.617021 (1005 3285);
PAINT WHITE (1005 3285);
FORCEPROP 1 LASTPIN (1000 3475) $PN 1
J 0
(1005 3437);
DISPLAY 0.617021 (1005 3437);
PAINT WHITE (1005 3437);
FORCEPROP 1 LAST PART_NUMBER G21796-072
J 0
(1040 3250);
DISPLAY 0.617021 (1040 3250);
PAINT BLUE (1040 3250);
FORCEPROP 1 LAST MATERIAL CHIP
J 0
(1040 3300);
DISPLAY 0.617021 (1040 3300);
PAINT SKYBLUE (1040 3300);
FORCEPROP 1 LAST WATTAGE 1/16W
J 0
(1040 3350);
DISPLAY 0.617021 (1040 3350);
PAINT SKYBLUE (1040 3350);
FORCEPROP 2 LAST CDS_LIB mstr_discrete
J 0
(1000 3375);
DISPLAY 0.829787 (1000 3375);
PAINT ORANGE (1000 3375);
DISPLAY INVISIBLE (1000 3375);
FORCEPROP 2 LAST SEC_TYPE 0402
J 0
(1050 3600);
DISPLAY 1.361702 (1050 3600);
PAINT ORANGE (1050 3600);
DISPLAY INVISIBLE (1050 3600);
FORCEPROP 2 LAST SIGNAL_MODEL DEFAULT_RESISTOR_4750OHM_2_1
J 0
(1050 3600);
PAINT MONO (1050 3600);
DISPLAY INVISIBLE (1050 3600);
FORCEPROP 2 LAST SEC 1
J 0
(1050 3600);
DISPLAY 0.914894 (1050 3600);
PAINT MONO (1050 3600);
DISPLAY INVISIBLE (1050 3600);
FORCEPROP 2 LAST CDS_LOCATION R8B10
J 0
(1045 3500);
DISPLAY 0.617021 (1045 3500);
PAINT AQUA (1045 3500);
DISPLAY INVISIBLE (1045 3500);
FORCEPROP 1 LAST PATH I16
J 0
(1050 3550);
DISPLAY 0.978723 (1050 3550);
PAINT WHITE (1050 3550);
DISPLAY INVISIBLE (1050 3550);
FORCEPROP 0 LAST ROOM HFI
J 0
(1050 3550);
DISPLAY 1.021277 (1050 3550);
PAINT ORANGE (1050 3550);
DISPLAY INVISIBLE (1050 3550);
FORCEADD RES..2
(750 3375);
FORCEPROP 1 LAST LOCATION R8B16
J 0
(795 3500);
DISPLAY 0.617021 (795 3500);
PAINT AQUA (795 3500);
FORCEPROP 1 LAST VALUE 4.75K
J 0
(795 3450);
DISPLAY 0.617021 (795 3450);
PAINT SKYBLUE (795 3450);
FORCEPROP 1 LAST TOLERANCE 1%
J 0
(795 3400);
DISPLAY 0.617021 (795 3400);
PAINT SKYBLUE (795 3400);
FORCEPROP 1 LAST MATERIAL CHIP
J 0
(790 3300);
DISPLAY 0.617021 (790 3300);
PAINT SKYBLUE (790 3300);
FORCEPROP 1 LAST WATTAGE 1/16W
J 0
(790 3350);
DISPLAY 0.617021 (790 3350);
PAINT SKYBLUE (790 3350);
FORCEPROP 1 LASTPIN (750 3275) $PN 2
J 0
(755 3285);
DISPLAY 0.617021 (755 3285);
PAINT WHITE (755 3285);
FORCEPROP 1 LASTPIN (750 3475) $PN 1
J 0
(755 3437);
DISPLAY 0.617021 (755 3437);
PAINT WHITE (755 3437);
FORCEPROP 1 LAST PACK_TYPE 0402
J 0
(790 3200);
DISPLAY 0.617021 (790 3200);
PAINT SKYBLUE (790 3200);
FORCEPROP 1 LAST PART_NUMBER G21796-072
J 0
(790 3250);
DISPLAY 0.617021 (790 3250);
PAINT BLUE (790 3250);
FORCEPROP 2 LAST CDS_LIB mstr_discrete
J 0
(750 3375);
DISPLAY 0.829787 (750 3375);
PAINT ORANGE (750 3375);
DISPLAY INVISIBLE (750 3375);
FORCEPROP 2 LAST SEC_TYPE 0402
J 0
(800 3600);
DISPLAY 1.361702 (800 3600);
PAINT ORANGE (800 3600);
DISPLAY INVISIBLE (800 3600);
FORCEPROP 2 LAST SIGNAL_MODEL DEFAULT_RESISTOR_4750OHM_2_1
J 0
(800 3600);
PAINT MONO (800 3600);
DISPLAY INVISIBLE (800 3600);
FORCEPROP 2 LAST SEC 1
J 0
(800 3600);
DISPLAY 0.914894 (800 3600);
PAINT MONO (800 3600);
DISPLAY INVISIBLE (800 3600);
FORCEPROP 2 LAST CDS_LOCATION R8B16
J 0
(795 3500);
DISPLAY 0.617021 (795 3500);
PAINT AQUA (795 3500);
DISPLAY INVISIBLE (795 3500);
FORCEPROP 1 LAST PATH I17
J 0
(800 3550);
DISPLAY 0.978723 (800 3550);
PAINT WHITE (800 3550);
DISPLAY INVISIBLE (800 3550);
FORCEPROP 0 LAST ROOM HFI
J 0
(800 3550);
DISPLAY 1.021277 (800 3550);
PAINT ORANGE (800 3550);
DISPLAY INVISIBLE (800 3550);
FORCEADD RES..2
(500 3375);
FORCEPROP 1 LAST LOCATION R8B17
J 0
(545 3500);
DISPLAY 0.617021 (545 3500);
PAINT AQUA (545 3500);
FORCEPROP 1 LAST PART_NUMBER G21796-072
J 0
(540 3250);
DISPLAY 0.617021 (540 3250);
PAINT BLUE (540 3250);
FORCEPROP 1 LAST VALUE 4.75K
J 0
(545 3450);
DISPLAY 0.617021 (545 3450);
PAINT SKYBLUE (545 3450);
FORCEPROP 1 LAST TOLERANCE 1%
J 0
(545 3400);
DISPLAY 0.617021 (545 3400);
PAINT SKYBLUE (545 3400);
FORCEPROP 1 LAST PACK_TYPE 0402
J 0
(540 3200);
DISPLAY 0.617021 (540 3200);
PAINT SKYBLUE (540 3200);
FORCEPROP 1 LAST MATERIAL CHIP
J 0
(540 3300);
DISPLAY 0.617021 (540 3300);
PAINT SKYBLUE (540 3300);
FORCEPROP 1 LAST WATTAGE 1/16W
J 0
(540 3350);
DISPLAY 0.617021 (540 3350);
PAINT SKYBLUE (540 3350);
FORCEPROP 1 LASTPIN (500 3275) $PN 2
J 0
(505 3285);
DISPLAY 0.617021 (505 3285);
PAINT WHITE (505 3285);
FORCEPROP 1 LASTPIN (500 3475) $PN 1
J 0
(505 3437);
DISPLAY 0.617021 (505 3437);
PAINT WHITE (505 3437);
FORCEPROP 2 LAST SIGNAL_MODEL DEFAULT_RESISTOR_4750OHM_2_1
J 0
(550 3600);
PAINT MONO (550 3600);
DISPLAY INVISIBLE (550 3600);
FORCEPROP 2 LAST SEC_TYPE 0402
J 0
(550 3600);
DISPLAY 1.361702 (550 3600);
PAINT ORANGE (550 3600);
DISPLAY INVISIBLE (550 3600);
FORCEPROP 2 LAST CDS_LIB mstr_discrete
J 0
(500 3375);
DISPLAY 0.829787 (500 3375);
PAINT ORANGE (500 3375);
DISPLAY INVISIBLE (500 3375);
FORCEPROP 2 LAST SEC 1
J 0
(550 3600);
DISPLAY 0.914894 (550 3600);
PAINT MONO (550 3600);
DISPLAY INVISIBLE (550 3600);
FORCEPROP 2 LAST CDS_LOCATION R8B17
J 0
(545 3500);
DISPLAY 0.617021 (545 3500);
PAINT AQUA (545 3500);
DISPLAY INVISIBLE (545 3500);
FORCEPROP 1 LAST PATH I18
J 0
(550 3550);
DISPLAY 0.978723 (550 3550);
PAINT WHITE (550 3550);
DISPLAY INVISIBLE (550 3550);
FORCEPROP 0 LAST ROOM HFI
J 0
(550 3550);
DISPLAY 1.021277 (550 3550);
PAINT ORANGE (550 3550);
DISPLAY INVISIBLE (550 3550);
FORCEADD GND..1
(-625 2350);
FORCEPROP 3 LASTPIN (-625 2400) SIG_NAME GND\g
J 0
(-615 2410);
DISPLAY 0.659574 (-615 2410);
PAINT MONO (-615 2410);
DISPLAY INVISIBLE (-615 2410);
FORCEPROP 1 LAST VOLTAGE 0.0V
J 0
(-670 2307);
DISPLAY 0.340426 (-670 2307);
PAINT SKYBLUE (-670 2307);
DISPLAY INVISIBLE (-670 2307);
FORCEPROP 2 LAST CDS_LIB mstr_symbols
J 0
(-625 2350);
DISPLAY 1.340426 (-625 2350);
PAINT MONO (-625 2350);
DISPLAY INVISIBLE (-625 2350);
FORCEPROP 1 LAST SIZE 1B
J 0
(-550 2300);
DISPLAY 1.170213 (-550 2300);
PAINT AQUA (-550 2300);
DISPLAY INVISIBLE (-550 2300);
FORCEPROP 1 LAST PATH I2
J 0
(-550 2350);
DISPLAY 0.872340 (-550 2350);
PAINT AQUA (-550 2350);
DISPLAY INVISIBLE (-550 2350);
FORCEPROP 1 LAST BODY_TYPE PLUMBING
J 0
(-670 2307);
DISPLAY 0.340426 (-670 2307);
PAINT GREEN (-670 2307);
DISPLAY INVISIBLE (-670 2307);
FORCEPROP 1 LAST HDL_POWER GND
J 0
(-625 2500);
DISPLAY 1.170213 (-625 2500);
PAINT GREEN (-625 2500);
DISPLAY INVISIBLE (-625 2500);
FORCEADD RES..2
R 2
(-750 3350);
FORCEPROP 1 LAST LOCATION R8B18
J 2
(-795 3475);
DISPLAY 0.617021 (-795 3475);
PAINT AQUA (-795 3475);
FORCEPROP 1 LAST PART_NUMBER G21796-072
J 2
(-790 3225);
DISPLAY 0.617021 (-790 3225);
PAINT BLUE (-790 3225);
FORCEPROP 1 LAST VALUE 4.75K
J 2
(-795 3425);
DISPLAY 0.617021 (-795 3425);
PAINT SKYBLUE (-795 3425);
FORCEPROP 1 LAST TOLERANCE 1%
J 2
(-795 3375);
DISPLAY 0.617021 (-795 3375);
PAINT SKYBLUE (-795 3375);
FORCEPROP 1 LAST MATERIAL CHIP
J 2
(-790 3275);
DISPLAY 0.617021 (-790 3275);
PAINT SKYBLUE (-790 3275);
FORCEPROP 1 LAST WATTAGE 1/16W
J 2
(-790 3325);
DISPLAY 0.617021 (-790 3325);
PAINT SKYBLUE (-790 3325);
FORCEPROP 1 LASTPIN (-750 3250) $PN 2
J 2
(-755 3260);
DISPLAY 0.617021 (-755 3260);
PAINT WHITE (-755 3260);
FORCEPROP 1 LASTPIN (-750 3450) $PN 1
J 2
(-755 3412);
DISPLAY 0.617021 (-755 3412);
PAINT WHITE (-755 3412);
FORCEPROP 1 LAST PACK_TYPE 0402
J 2
(-790 3175);
DISPLAY 0.617021 (-790 3175);
PAINT SKYBLUE (-790 3175);
FORCEPROP 2 LAST SIGNAL_MODEL DEFAULT_RESISTOR_4750OHM_2_1
J 0
(-800 3575);
PAINT MONO (-800 3575);
DISPLAY INVISIBLE (-800 3575);
FORCEPROP 2 LAST CDS_LIB mstr_discrete
J 2
(-750 3350);
DISPLAY 0.829787 (-750 3350);
PAINT ORANGE (-750 3350);
DISPLAY INVISIBLE (-750 3350);
FORCEPROP 2 LAST SEC_TYPE 0402
J 2
(-800 3575);
DISPLAY 1.361702 (-800 3575);
PAINT ORANGE (-800 3575);
DISPLAY INVISIBLE (-800 3575);
FORCEPROP 2 LAST SEC 1
J 2
(-800 3575);
DISPLAY 0.914894 (-800 3575);
PAINT MONO (-800 3575);
DISPLAY INVISIBLE (-800 3575);
FORCEPROP 2 LAST CDS_LOCATION R8B18
J 2
(-795 3475);
DISPLAY 0.617021 (-795 3475);
PAINT AQUA (-795 3475);
DISPLAY INVISIBLE (-795 3475);
FORCEPROP 1 LAST PATH I20
J 2
(-800 3525);
DISPLAY 0.978723 (-800 3525);
PAINT WHITE (-800 3525);
DISPLAY INVISIBLE (-800 3525);
FORCEPROP 0 LAST ROOM HFI
J 0
(-775 3525);
DISPLAY 1.021277 (-775 3525);
PAINT ORANGE (-775 3525);
DISPLAY INVISIBLE (-775 3525);
FORCEADD RES..2
R 2
(-1125 3350);
FORCEPROP 1 LAST LOCATION R8B19
J 2
(-1170 3475);
DISPLAY 0.617021 (-1170 3475);
PAINT AQUA (-1170 3475);
FORCEPROP 1 LAST PART_NUMBER G21796-072
J 2
(-1165 3225);
DISPLAY 0.617021 (-1165 3225);
PAINT BLUE (-1165 3225);
FORCEPROP 1 LAST TOLERANCE 1%
J 2
(-1170 3375);
DISPLAY 0.617021 (-1170 3375);
PAINT SKYBLUE (-1170 3375);
FORCEPROP 1 LAST PACK_TYPE 0402
J 2
(-1165 3175);
DISPLAY 0.617021 (-1165 3175);
PAINT SKYBLUE (-1165 3175);
FORCEPROP 1 LAST MATERIAL CHIP
J 2
(-1165 3275);
DISPLAY 0.617021 (-1165 3275);
PAINT SKYBLUE (-1165 3275);
FORCEPROP 1 LAST WATTAGE 1/16W
J 2
(-1165 3325);
DISPLAY 0.617021 (-1165 3325);
PAINT SKYBLUE (-1165 3325);
FORCEPROP 1 LASTPIN (-1125 3250) $PN 2
J 2
(-1130 3260);
DISPLAY 0.617021 (-1130 3260);
PAINT WHITE (-1130 3260);
FORCEPROP 1 LASTPIN (-1125 3450) $PN 1
J 2
(-1130 3412);
DISPLAY 0.617021 (-1130 3412);
PAINT WHITE (-1130 3412);
FORCEPROP 1 LAST VALUE 4.75K
J 2
(-1170 3425);
DISPLAY 0.617021 (-1170 3425);
PAINT SKYBLUE (-1170 3425);
FORCEPROP 2 LAST SIGNAL_MODEL DEFAULT_RESISTOR_4750OHM_2_1
J 0
(-1175 3575);
PAINT MONO (-1175 3575);
DISPLAY INVISIBLE (-1175 3575);
FORCEPROP 2 LAST CDS_LIB mstr_discrete
J 2
(-1125 3350);
DISPLAY 0.829787 (-1125 3350);
PAINT ORANGE (-1125 3350);
DISPLAY INVISIBLE (-1125 3350);
FORCEPROP 2 LAST SEC_TYPE 0402
J 2
(-1175 3575);
DISPLAY 1.361702 (-1175 3575);
PAINT ORANGE (-1175 3575);
DISPLAY INVISIBLE (-1175 3575);
FORCEPROP 2 LAST SEC 1
J 2
(-1175 3575);
DISPLAY 0.914894 (-1175 3575);
PAINT MONO (-1175 3575);
DISPLAY INVISIBLE (-1175 3575);
FORCEPROP 2 LAST CDS_LOCATION R8B19
J 2
(-1170 3475);
DISPLAY 0.617021 (-1170 3475);
PAINT AQUA (-1170 3475);
DISPLAY INVISIBLE (-1170 3475);
FORCEPROP 1 LAST PATH I21
J 2
(-1175 3525);
DISPLAY 0.978723 (-1175 3525);
PAINT WHITE (-1175 3525);
DISPLAY INVISIBLE (-1175 3525);
FORCEPROP 0 LAST ROOM HFI
J 0
(-1150 3525);
DISPLAY 1.021277 (-1150 3525);
PAINT ORANGE (-1150 3525);
DISPLAY INVISIBLE (-1150 3525);
FORCEADD RES..2
R 2
(-1500 3350);
FORCEPROP 1 LAST LOCATION R8B5
J 2
(-1545 3475);
DISPLAY 0.617021 (-1545 3475);
PAINT AQUA (-1545 3475);
FORCEPROP 1 LAST PART_NUMBER G21796-072
J 2
(-1540 3225);
DISPLAY 0.617021 (-1540 3225);
PAINT BLUE (-1540 3225);
FORCEPROP 1 LAST VALUE 4.75K
J 2
(-1545 3425);
DISPLAY 0.617021 (-1545 3425);
PAINT SKYBLUE (-1545 3425);
FORCEPROP 1 LAST TOLERANCE 1%
J 2
(-1545 3375);
DISPLAY 0.617021 (-1545 3375);
PAINT SKYBLUE (-1545 3375);
FORCEPROP 1 LAST PACK_TYPE 0402
J 2
(-1540 3175);
DISPLAY 0.617021 (-1540 3175);
PAINT SKYBLUE (-1540 3175);
FORCEPROP 1 LAST MATERIAL CHIP
J 2
(-1540 3275);
DISPLAY 0.617021 (-1540 3275);
PAINT SKYBLUE (-1540 3275);
FORCEPROP 1 LAST WATTAGE 1/16W
J 2
(-1540 3325);
DISPLAY 0.617021 (-1540 3325);
PAINT SKYBLUE (-1540 3325);
FORCEPROP 1 LASTPIN (-1500 3250) $PN 2
J 2
(-1505 3260);
DISPLAY 0.617021 (-1505 3260);
PAINT WHITE (-1505 3260);
FORCEPROP 1 LASTPIN (-1500 3450) $PN 1
J 2
(-1505 3412);
DISPLAY 0.617021 (-1505 3412);
PAINT WHITE (-1505 3412);
FORCEPROP 2 LAST SIGNAL_MODEL DEFAULT_RESISTOR_4750OHM_2_1
J 0
(-1550 3575);
PAINT MONO (-1550 3575);
DISPLAY INVISIBLE (-1550 3575);
FORCEPROP 2 LAST CDS_LIB mstr_discrete
J 2
(-1500 3350);
DISPLAY 0.829787 (-1500 3350);
PAINT ORANGE (-1500 3350);
DISPLAY INVISIBLE (-1500 3350);
FORCEPROP 2 LAST SEC_TYPE 0402
J 2
(-1550 3575);
DISPLAY 1.361702 (-1550 3575);
PAINT ORANGE (-1550 3575);
DISPLAY INVISIBLE (-1550 3575);
FORCEPROP 2 LAST SEC 1
J 2
(-1550 3575);
DISPLAY 0.914894 (-1550 3575);
PAINT MONO (-1550 3575);
DISPLAY INVISIBLE (-1550 3575);
FORCEPROP 2 LAST CDS_LOCATION R8B5
J 2
(-1545 3475);
DISPLAY 0.617021 (-1545 3475);
PAINT AQUA (-1545 3475);
DISPLAY INVISIBLE (-1545 3475);
FORCEPROP 1 LAST PATH I22
J 2
(-1550 3525);
DISPLAY 0.978723 (-1550 3525);
PAINT WHITE (-1550 3525);
DISPLAY INVISIBLE (-1550 3525);
FORCEPROP 0 LAST ROOM HFI
J 0
(-1525 3525);
DISPLAY 1.021277 (-1525 3525);
PAINT ORANGE (-1525 3525);
DISPLAY INVISIBLE (-1525 3525);
FORCEADD RES..2
R 2
(-1875 3350);
FORCEPROP 1 LAST LOCATION R8B3
J 2
(-1920 3475);
DISPLAY 0.617021 (-1920 3475);
PAINT AQUA (-1920 3475);
FORCEPROP 1 LAST PART_NUMBER G21796-072
J 2
(-1915 3225);
DISPLAY 0.617021 (-1915 3225);
PAINT BLUE (-1915 3225);
FORCEPROP 1 LAST VALUE 4.75K
J 2
(-1920 3425);
DISPLAY 0.617021 (-1920 3425);
PAINT SKYBLUE (-1920 3425);
FORCEPROP 1 LAST TOLERANCE 1%
J 2
(-1920 3375);
DISPLAY 0.617021 (-1920 3375);
PAINT SKYBLUE (-1920 3375);
FORCEPROP 1 LAST PACK_TYPE 0402
J 2
(-1915 3175);
DISPLAY 0.617021 (-1915 3175);
PAINT SKYBLUE (-1915 3175);
FORCEPROP 1 LAST MATERIAL CHIP
J 2
(-1915 3275);
DISPLAY 0.617021 (-1915 3275);
PAINT SKYBLUE (-1915 3275);
FORCEPROP 1 LAST WATTAGE 1/16W
J 2
(-1915 3325);
DISPLAY 0.617021 (-1915 3325);
PAINT SKYBLUE (-1915 3325);
FORCEPROP 1 LASTPIN (-1875 3250) $PN 2
J 2
(-1880 3260);
DISPLAY 0.617021 (-1880 3260);
PAINT WHITE (-1880 3260);
FORCEPROP 1 LASTPIN (-1875 3450) $PN 1
J 2
(-1880 3412);
DISPLAY 0.617021 (-1880 3412);
PAINT WHITE (-1880 3412);
FORCEPROP 2 LAST SIGNAL_MODEL DEFAULT_RESISTOR_4750OHM_2_1
J 0
(-1925 3575);
PAINT MONO (-1925 3575);
DISPLAY INVISIBLE (-1925 3575);
FORCEPROP 2 LAST CDS_LIB mstr_discrete
J 2
(-1875 3350);
DISPLAY 0.829787 (-1875 3350);
PAINT ORANGE (-1875 3350);
DISPLAY INVISIBLE (-1875 3350);
FORCEPROP 2 LAST SEC_TYPE 0402
J 2
(-1925 3575);
DISPLAY 1.361702 (-1925 3575);
PAINT ORANGE (-1925 3575);
DISPLAY INVISIBLE (-1925 3575);
FORCEPROP 2 LAST SEC 1
J 2
(-1925 3575);
DISPLAY 0.914894 (-1925 3575);
PAINT MONO (-1925 3575);
DISPLAY INVISIBLE (-1925 3575);
FORCEPROP 2 LAST CDS_LOCATION R8B3
J 2
(-1920 3475);
DISPLAY 0.617021 (-1920 3475);
PAINT AQUA (-1920 3475);
DISPLAY INVISIBLE (-1920 3475);
FORCEPROP 1 LAST PATH I24
J 2
(-1925 3525);
DISPLAY 0.978723 (-1925 3525);
PAINT WHITE (-1925 3525);
DISPLAY INVISIBLE (-1925 3525);
FORCEPROP 0 LAST ROOM HFI
J 0
(-1900 3575);
DISPLAY 1.021277 (-1900 3575);
PAINT ORANGE (-1900 3575);
DISPLAY INVISIBLE (-1900 3575);
FORCEADD OFFPAGE..5
(-2950 3100);
FORCEPROP 2 LAST $XR0 29 
J 0
(-3204 3100);
DISPLAY 0.638298 (-3204 3100);
PAINT MONO (-3204 3100);
FORCEPROP 2 LAST CDS_LIB mstr_standard
J 0
(-2950 3100);
DISPLAY 1.340426 (-2950 3100);
PAINT MONO (-2950 3100);
DISPLAY INVISIBLE (-2950 3100);
FORCEPROP 2 LAST PATH I25
J 0
(-3200 3150);
DISPLAY 1.021277 (-3200 3150);
PAINT ORANGE (-3200 3150);
DISPLAY INVISIBLE (-3200 3150);
FORCEPROP 1 LAST OFFPAGE TRUE
J 0
(-2625 2975);
DISPLAY 0.829787 (-2625 2975);
PAINT GREEN (-2625 2975);
DISPLAY INVISIBLE (-2625 2975);
FORCEPROP 1 LAST COMMENT_BODY TRUE
J 0
(-2850 3025);
DISPLAY 1.170213 (-2850 3025);
PAINT PEACH (-2850 3025);
DISPLAY INVISIBLE (-2850 3025);
FORCEADD OFFPAGE..1
(-2950 3050);
FORCEPROP 2 LAST $XR0 29 
J 0
(-3201 3050);
DISPLAY 0.638298 (-3201 3050);
PAINT MONO (-3201 3050);
FORCEPROP 2 LAST CDS_LIB mstr_standard
J 0
(-2950 3050);
DISPLAY 1.340426 (-2950 3050);
PAINT MONO (-2950 3050);
DISPLAY INVISIBLE (-2950 3050);
FORCEPROP 2 LAST PATH I26
J 0
(-3225 3100);
DISPLAY 1.021277 (-3225 3100);
PAINT ORANGE (-3225 3100);
DISPLAY INVISIBLE (-3225 3100);
FORCEPROP 1 LAST OFFPAGE TRUE
J 0
(-2625 2925);
DISPLAY 0.829787 (-2625 2925);
PAINT GREEN (-2625 2925);
DISPLAY INVISIBLE (-2625 2925);
FORCEPROP 1 LAST COMMENT_BODY TRUE
J 0
(-2825 2950);
DISPLAY 1.170213 (-2825 2950);
PAINT PEACH (-2825 2950);
DISPLAY INVISIBLE (-2825 2950);
FORCEADD OFFPAGE..1
(-2950 2850);
FORCEPROP 2 LAST $XR0 29 
J 0
(-3201 2850);
DISPLAY 0.638298 (-3201 2850);
PAINT MONO (-3201 2850);
FORCEPROP 2 LAST CDS_LIB mstr_standard
J 0
(-2950 2850);
DISPLAY 1.340426 (-2950 2850);
PAINT MONO (-2950 2850);
DISPLAY INVISIBLE (-2950 2850);
FORCEPROP 2 LAST PATH I27
J 0
(-3225 2900);
DISPLAY 1.021277 (-3225 2900);
PAINT ORANGE (-3225 2900);
DISPLAY INVISIBLE (-3225 2900);
FORCEPROP 1 LAST OFFPAGE TRUE
J 0
(-2625 2725);
DISPLAY 0.829787 (-2625 2725);
PAINT GREEN (-2625 2725);
DISPLAY INVISIBLE (-2625 2725);
FORCEPROP 1 LAST COMMENT_BODY TRUE
J 0
(-2825 2750);
DISPLAY 1.170213 (-2825 2750);
PAINT PEACH (-2825 2750);
DISPLAY INVISIBLE (-2825 2750);
FORCEADD OFFPAGE..5
(-2950 2900);
FORCEPROP 2 LAST $XR0 29 
J 0
(-3204 2900);
DISPLAY 0.638298 (-3204 2900);
PAINT MONO (-3204 2900);
FORCEPROP 2 LAST CDS_LIB mstr_standard
J 0
(-2950 2900);
DISPLAY 1.340426 (-2950 2900);
PAINT MONO (-2950 2900);
DISPLAY INVISIBLE (-2950 2900);
FORCEPROP 2 LAST PATH I28
J 0
(-3200 2950);
DISPLAY 1.021277 (-3200 2950);
PAINT ORANGE (-3200 2950);
DISPLAY INVISIBLE (-3200 2950);
FORCEPROP 1 LAST OFFPAGE TRUE
J 0
(-2625 2775);
DISPLAY 0.829787 (-2625 2775);
PAINT GREEN (-2625 2775);
DISPLAY INVISIBLE (-2625 2775);
FORCEPROP 1 LAST COMMENT_BODY TRUE
J 0
(-2850 2825);
DISPLAY 1.170213 (-2850 2825);
PAINT PEACH (-2850 2825);
DISPLAY INVISIBLE (-2850 2825);
FORCEADD OFFPAGE..1
(-2950 2700);
FORCEPROP 2 LAST $XR1 190 
J 0
(-3322 2700);
DISPLAY 0.638298 (-3322 2700);
PAINT MONO (-3322 2700);
FORCEPROP 2 LAST $XR0 231 
J 0
(-3202 2700);
DISPLAY 0.638298 (-3202 2700);
PAINT MONO (-3202 2700);
FORCEPROP 2 LAST CDS_LIB mstr_standard
J 0
(-2950 2700);
DISPLAY 0.829787 (-2950 2700);
PAINT ORANGE (-2950 2700);
DISPLAY INVISIBLE (-2950 2700);
FORCEPROP 2 LAST PATH I29
J 0
(-3250 2750);
DISPLAY 1.021277 (-3250 2750);
PAINT ORANGE (-3250 2750);
DISPLAY INVISIBLE (-3250 2750);
FORCEPROP 1 LAST OFFPAGE TRUE
J 0
(-2625 2575);
DISPLAY 0.829787 (-2625 2575);
PAINT GREEN (-2625 2575);
DISPLAY INVISIBLE (-2625 2575);
FORCEPROP 1 LAST COMMENT_BODY TRUE
J 0
(-2825 2600);
DISPLAY 1.170213 (-2825 2600);
PAINT PEACH (-2825 2600);
DISPLAY INVISIBLE (-2825 2600);
FORCEADD OFFPAGE..4
(3100 3050);
FORCEPROP 2 LAST $XR0 29 
J 0
(3286 3050);
DISPLAY 0.638298 (3286 3050);
PAINT MONO (3286 3050);
FORCEPROP 2 LAST CDS_LIB mstr_standard
J 0
(3100 3050);
DISPLAY 1.340426 (3100 3050);
PAINT MONO (3100 3050);
DISPLAY INVISIBLE (3100 3050);
FORCEPROP 2 LAST PATH I3
J 0
(3325 3100);
DISPLAY 1.021277 (3325 3100);
PAINT ORANGE (3325 3100);
DISPLAY INVISIBLE (3325 3100);
FORCEPROP 1 LAST OFFPAGE TRUE
J 0
(3425 2925);
DISPLAY 0.829787 (3425 2925);
PAINT GREEN (3425 2925);
DISPLAY INVISIBLE (3425 2925);
FORCEPROP 1 LAST COMMENT_BODY TRUE
J 0
(3075 2950);
DISPLAY 1.170213 (3075 2950);
PAINT PEACH (3075 2950);
DISPLAY INVISIBLE (3075 2950);
FORCEADD PVPP_ABC..1
(-1875 3650);
FORCEPROP 3 LASTPIN (-1875 3600) SIG_NAME PVPP_ABC\g
J 0
(-1865 3610);
DISPLAY 0.659574 (-1865 3610);
PAINT MONO (-1865 3610);
DISPLAY INVISIBLE (-1865 3610);
FORCEPROP 1 LAST VOLTAGE 2.5V
J 0
(-1920 3607);
DISPLAY 0.340426 (-1920 3607);
PAINT SKYBLUE (-1920 3607);
DISPLAY INVISIBLE (-1920 3607);
FORCEPROP 2 LAST BOM_COST PVPP_KLM_VR
J 0
(-1800 3750);
PAINT MONO (-1800 3750);
DISPLAY INVISIBLE (-1800 3750);
FORCEPROP 2 LAST CDS_LIB mstr_symbols
J 0
(-1875 3650);
PAINT ORANGE (-1875 3650);
DISPLAY INVISIBLE (-1875 3650);
FORCEPROP 1 LAST PATH I30
J 0
(-1825 3675);
DISPLAY 0.872340 (-1825 3675);
PAINT AQUA (-1825 3675);
DISPLAY INVISIBLE (-1825 3675);
FORCEPROP 2 LAST ROOM PVPP_KLM_VR
J 0
(-1625 3750);
PAINT ORANGE (-1625 3750);
DISPLAY INVISIBLE (-1625 3750);
FORCEPROP 1 LAST BODY_TYPE PLUMBING
J 0
(-1920 3607);
DISPLAY 0.340426 (-1920 3607);
PAINT GREEN (-1920 3607);
DISPLAY INVISIBLE (-1920 3607);
FORCEPROP 1 LAST HDL_POWER PVPP_ABC
J 1
(-1875 3700);
DISPLAY 0.872340 (-1875 3700);
PAINT GREEN (-1875 3700);
DISPLAY INVISIBLE (-1875 3700);
FORCEADD PVPP_ABC..1
(-675 3650);
FORCEPROP 3 LASTPIN (-675 3600) SIG_NAME PVPP_ABC\g
J 0
(-665 3610);
DISPLAY 0.659574 (-665 3610);
PAINT MONO (-665 3610);
DISPLAY INVISIBLE (-665 3610);
FORCEPROP 1 LAST VOLTAGE 2.5V
J 0
(-720 3607);
DISPLAY 0.340426 (-720 3607);
PAINT SKYBLUE (-720 3607);
DISPLAY INVISIBLE (-720 3607);
FORCEPROP 2 LAST BOM_COST PVPP_KLM_VR
J 0
(-600 3750);
PAINT MONO (-600 3750);
DISPLAY INVISIBLE (-600 3750);
FORCEPROP 2 LAST CDS_LIB mstr_symbols
J 0
(-675 3650);
PAINT ORANGE (-675 3650);
DISPLAY INVISIBLE (-675 3650);
FORCEPROP 1 LAST PATH I31
J 0
(-625 3675);
DISPLAY 0.872340 (-625 3675);
PAINT AQUA (-625 3675);
DISPLAY INVISIBLE (-625 3675);
FORCEPROP 2 LAST ROOM PVPP_KLM_VR
J 0
(-425 3750);
PAINT ORANGE (-425 3750);
DISPLAY INVISIBLE (-425 3750);
FORCEPROP 1 LAST BODY_TYPE PLUMBING
J 0
(-720 3607);
DISPLAY 0.340426 (-720 3607);
PAINT GREEN (-720 3607);
DISPLAY INVISIBLE (-720 3607);
FORCEPROP 1 LAST HDL_POWER PVPP_ABC
J 1
(-675 3700);
DISPLAY 0.872340 (-675 3700);
PAINT GREEN (-675 3700);
DISPLAY INVISIBLE (-675 3700);
FORCEADD PVPP_ABC..1
(2250 3700);
FORCEPROP 3 LASTPIN (2250 3650) SIG_NAME PVPP_ABC\g
J 0
(2260 3660);
DISPLAY 0.659574 (2260 3660);
PAINT MONO (2260 3660);
DISPLAY INVISIBLE (2260 3660);
FORCEPROP 1 LAST VOLTAGE 2.5V
J 0
(2205 3657);
DISPLAY 0.340426 (2205 3657);
PAINT SKYBLUE (2205 3657);
DISPLAY INVISIBLE (2205 3657);
FORCEPROP 2 LAST BOM_COST PVPP_KLM_VR
J 0
(2325 3800);
PAINT MONO (2325 3800);
DISPLAY INVISIBLE (2325 3800);
FORCEPROP 2 LAST CDS_LIB mstr_symbols
J 0
(2250 3700);
PAINT ORANGE (2250 3700);
DISPLAY INVISIBLE (2250 3700);
FORCEPROP 1 LAST PATH I32
J 0
(2300 3725);
DISPLAY 0.872340 (2300 3725);
PAINT AQUA (2300 3725);
DISPLAY INVISIBLE (2300 3725);
FORCEPROP 2 LAST ROOM PVPP_KLM_VR
J 0
(2500 3800);
PAINT ORANGE (2500 3800);
DISPLAY INVISIBLE (2500 3800);
FORCEPROP 1 LAST BODY_TYPE PLUMBING
J 0
(2205 3657);
DISPLAY 0.340426 (2205 3657);
PAINT GREEN (2205 3657);
DISPLAY INVISIBLE (2205 3657);
FORCEPROP 1 LAST HDL_POWER PVPP_ABC
J 1
(2250 3750);
DISPLAY 0.872340 (2250 3750);
PAINT GREEN (2250 3750);
DISPLAY INVISIBLE (2250 3750);
FORCEADD P3V3..1
(425 3650);
FORCEPROP 3 LASTPIN (425 3600) SIG_NAME P3V3\g
J 0
(435 3610);
DISPLAY 0.659574 (435 3610);
PAINT MONO (435 3610);
DISPLAY INVISIBLE (435 3610);
FORCEPROP 1 LAST VOLTAGE 3.3V
J 0
(380 3607);
DISPLAY 0.340426 (380 3607);
PAINT SKYBLUE (380 3607);
DISPLAY INVISIBLE (380 3607);
FORCEPROP 2 LAST CDS_LIB mstr_symbols
J 0
(425 3650);
PAINT MONO (425 3650);
DISPLAY INVISIBLE (425 3650);
FORCEPROP 1 LAST SIZE 1B
J 0
(470 3672);
DISPLAY 0.340426 (470 3672);
PAINT GREEN (470 3672);
DISPLAY INVISIBLE (470 3672);
FORCEPROP 1 LAST PATH I33
J 0
(470 3652);
DISPLAY 0.340426 (470 3652);
PAINT GREEN (470 3652);
DISPLAY INVISIBLE (470 3652);
FORCEPROP 1 LAST BODY_TYPE PLUMBING
J 0
(380 3607);
DISPLAY 0.340426 (380 3607);
PAINT GREEN (380 3607);
DISPLAY INVISIBLE (380 3607);
FORCEPROP 1 LAST HDL_POWER P3V3
J 0
(100 3525);
DISPLAY 0.872340 (100 3525);
PAINT ORANGE (100 3525);
DISPLAY INVISIBLE (100 3525);
FORCEADD RES..2
(1500 3375);
FORCEPROP 1 LAST LOCATION R8B13
J 0
(1545 3500);
DISPLAY 0.617021 (1545 3500);
PAINT AQUA (1545 3500);
FORCEPROP 1 LAST PART_NUMBER G21796-336
J 0
(1540 3250);
DISPLAY 0.617021 (1540 3250);
PAINT BLUE (1540 3250);
FORCEPROP 1 LAST VALUE 1.8K
J 0
(1545 3450);
DISPLAY 0.617021 (1545 3450);
PAINT SKYBLUE (1545 3450);
FORCEPROP 1 LAST TOLERANCE 1%
J 0
(1545 3400);
DISPLAY 0.617021 (1545 3400);
PAINT SKYBLUE (1545 3400);
FORCEPROP 1 LAST PACK_TYPE 0402
J 0
(1540 3200);
DISPLAY 0.617021 (1540 3200);
PAINT SKYBLUE (1540 3200);
FORCEPROP 1 LAST MATERIAL CHIP
J 0
(1540 3300);
DISPLAY 0.617021 (1540 3300);
PAINT SKYBLUE (1540 3300);
FORCEPROP 1 LAST WATTAGE 1/16W
J 0
(1540 3350);
DISPLAY 0.617021 (1540 3350);
PAINT SKYBLUE (1540 3350);
FORCEPROP 1 LASTPIN (1500 3275) $PN 2
J 0
(1505 3285);
DISPLAY 0.617021 (1505 3285);
PAINT ORANGE (1505 3285);
FORCEPROP 1 LASTPIN (1500 3475) $PN 1
J 0
(1505 3437);
DISPLAY 0.617021 (1505 3437);
PAINT ORANGE (1505 3437);
FORCEPROP 2 LAST CDS_LIB mstr_discrete
J 0
(1500 3375);
PAINT ORANGE (1500 3375);
DISPLAY INVISIBLE (1500 3375);
FORCEPROP 2 LAST SEC_TYPE 0402
J 0
(1550 3600);
DISPLAY 1.021277 (1550 3600);
PAINT ORANGE (1550 3600);
DISPLAY INVISIBLE (1550 3600);
FORCEPROP 2 LAST SEC 1
J 0
(1550 3600);
DISPLAY 0.680851 (1550 3600);
PAINT MONO (1550 3600);
DISPLAY INVISIBLE (1550 3600);
FORCEPROP 2 LAST CDS_LOCATION R8B13
J 0
(1545 3500);
DISPLAY 0.617021 (1545 3500);
PAINT AQUA (1545 3500);
DISPLAY INVISIBLE (1545 3500);
FORCEPROP 1 LAST PATH I34
J 0
(1550 3550);
DISPLAY 0.978723 (1550 3550);
PAINT WHITE (1550 3550);
DISPLAY INVISIBLE (1550 3550);
FORCEPROP 0 LAST ROOM SMBUS_CPU0_STL
J 0
(1550 3600);
DISPLAY 1.021277 (1550 3600);
PAINT ORANGE (1550 3600);
DISPLAY INVISIBLE (1550 3600);
FORCEADD RES..2
(1725 3375);
FORCEPROP 1 LAST LOCATION R8B11
J 0
(1770 3500);
DISPLAY 0.617021 (1770 3500);
PAINT AQUA (1770 3500);
FORCEPROP 1 LAST PART_NUMBER G21796-336
J 0
(1765 3250);
DISPLAY 0.617021 (1765 3250);
PAINT BLUE (1765 3250);
FORCEPROP 1 LAST VALUE 1.8K
J 0
(1770 3450);
DISPLAY 0.617021 (1770 3450);
PAINT SKYBLUE (1770 3450);
FORCEPROP 1 LAST TOLERANCE 1%
J 0
(1770 3400);
DISPLAY 0.617021 (1770 3400);
PAINT SKYBLUE (1770 3400);
FORCEPROP 1 LAST PACK_TYPE 0402
J 0
(1765 3200);
DISPLAY 0.617021 (1765 3200);
PAINT SKYBLUE (1765 3200);
FORCEPROP 1 LAST MATERIAL CHIP
J 0
(1765 3300);
DISPLAY 0.617021 (1765 3300);
PAINT SKYBLUE (1765 3300);
FORCEPROP 1 LAST WATTAGE 1/16W
J 0
(1765 3350);
DISPLAY 0.617021 (1765 3350);
PAINT SKYBLUE (1765 3350);
FORCEPROP 1 LASTPIN (1725 3275) $PN 2
J 0
(1730 3285);
DISPLAY 0.617021 (1730 3285);
PAINT ORANGE (1730 3285);
FORCEPROP 1 LASTPIN (1725 3475) $PN 1
J 0
(1730 3437);
DISPLAY 0.617021 (1730 3437);
PAINT ORANGE (1730 3437);
FORCEPROP 2 LAST CDS_LIB mstr_discrete
J 0
(1725 3375);
PAINT ORANGE (1725 3375);
DISPLAY INVISIBLE (1725 3375);
FORCEPROP 2 LAST SEC_TYPE 0402
J 0
(1775 3600);
DISPLAY 1.021277 (1775 3600);
PAINT ORANGE (1775 3600);
DISPLAY INVISIBLE (1775 3600);
FORCEPROP 2 LAST SEC 1
J 0
(1775 3600);
DISPLAY 0.680851 (1775 3600);
PAINT MONO (1775 3600);
DISPLAY INVISIBLE (1775 3600);
FORCEPROP 2 LAST CDS_LOCATION R8B11
J 0
(1770 3500);
DISPLAY 0.617021 (1770 3500);
PAINT AQUA (1770 3500);
DISPLAY INVISIBLE (1770 3500);
FORCEPROP 1 LAST PATH I35
J 0
(1775 3550);
DISPLAY 0.978723 (1775 3550);
PAINT WHITE (1775 3550);
DISPLAY INVISIBLE (1775 3550);
FORCEPROP 0 LAST ROOM SMBUS_CPU0_STL
J 0
(1775 3600);
DISPLAY 1.021277 (1775 3600);
PAINT ORANGE (1775 3600);
DISPLAY INVISIBLE (1775 3600);
FORCEADD RES..2
(1975 3375);
FORCEPROP 1 LAST LOCATION R8B7
J 0
(2020 3500);
DISPLAY 0.617021 (2020 3500);
PAINT AQUA (2020 3500);
FORCEPROP 1 LAST PART_NUMBER G21796-336
J 0
(2015 3250);
DISPLAY 0.617021 (2015 3250);
PAINT BLUE (2015 3250);
FORCEPROP 1 LAST VALUE 1.8K
J 0
(2020 3450);
DISPLAY 0.617021 (2020 3450);
PAINT SKYBLUE (2020 3450);
FORCEPROP 1 LAST TOLERANCE 1%
J 0
(2020 3400);
DISPLAY 0.617021 (2020 3400);
PAINT SKYBLUE (2020 3400);
FORCEPROP 1 LAST PACK_TYPE 0402
J 0
(2015 3200);
DISPLAY 0.617021 (2015 3200);
PAINT SKYBLUE (2015 3200);
FORCEPROP 1 LAST MATERIAL CHIP
J 0
(2015 3300);
DISPLAY 0.617021 (2015 3300);
PAINT SKYBLUE (2015 3300);
FORCEPROP 1 LASTPIN (1975 3275) $PN 2
J 0
(1980 3285);
DISPLAY 0.617021 (1980 3285);
PAINT ORANGE (1980 3285);
FORCEPROP 1 LASTPIN (1975 3475) $PN 1
J 0
(1980 3437);
DISPLAY 0.617021 (1980 3437);
PAINT ORANGE (1980 3437);
FORCEPROP 1 LAST WATTAGE 1/16W
J 0
(2015 3350);
DISPLAY 0.617021 (2015 3350);
PAINT SKYBLUE (2015 3350);
FORCEPROP 2 LAST CDS_LIB mstr_discrete
J 0
(1975 3375);
PAINT ORANGE (1975 3375);
DISPLAY INVISIBLE (1975 3375);
FORCEPROP 2 LAST SEC_TYPE 0402
J 0
(2025 3600);
DISPLAY 1.021277 (2025 3600);
PAINT ORANGE (2025 3600);
DISPLAY INVISIBLE (2025 3600);
FORCEPROP 2 LAST SEC 1
J 0
(2025 3600);
DISPLAY 0.680851 (2025 3600);
PAINT MONO (2025 3600);
DISPLAY INVISIBLE (2025 3600);
FORCEPROP 2 LAST CDS_LOCATION R8B7
J 0
(2020 3500);
DISPLAY 0.617021 (2020 3500);
PAINT AQUA (2020 3500);
DISPLAY INVISIBLE (2020 3500);
FORCEPROP 1 LAST PATH I36
J 0
(2025 3550);
DISPLAY 0.978723 (2025 3550);
PAINT WHITE (2025 3550);
DISPLAY INVISIBLE (2025 3550);
FORCEPROP 0 LAST ROOM SMBUS_CPU0_STL
J 0
(2025 3600);
DISPLAY 1.021277 (2025 3600);
PAINT ORANGE (2025 3600);
DISPLAY INVISIBLE (2025 3600);
FORCEADD RES..2
(2250 3375);
FORCEPROP 1 LAST LOCATION R8B6
J 0
(2295 3500);
DISPLAY 0.617021 (2295 3500);
PAINT AQUA (2295 3500);
FORCEPROP 1 LAST PART_NUMBER G21796-336
J 0
(2290 3250);
DISPLAY 0.617021 (2290 3250);
PAINT BLUE (2290 3250);
FORCEPROP 1 LAST VALUE 1.8K
J 0
(2295 3450);
DISPLAY 0.617021 (2295 3450);
PAINT SKYBLUE (2295 3450);
FORCEPROP 1 LAST TOLERANCE 1%
J 0
(2295 3400);
DISPLAY 0.617021 (2295 3400);
PAINT SKYBLUE (2295 3400);
FORCEPROP 1 LAST PACK_TYPE 0402
J 0
(2290 3200);
DISPLAY 0.617021 (2290 3200);
PAINT SKYBLUE (2290 3200);
FORCEPROP 1 LAST MATERIAL CHIP
J 0
(2290 3300);
DISPLAY 0.617021 (2290 3300);
PAINT SKYBLUE (2290 3300);
FORCEPROP 1 LAST WATTAGE 1/16W
J 0
(2290 3350);
DISPLAY 0.617021 (2290 3350);
PAINT SKYBLUE (2290 3350);
FORCEPROP 1 LASTPIN (2250 3275) $PN 2
J 0
(2255 3285);
DISPLAY 0.617021 (2255 3285);
PAINT ORANGE (2255 3285);
FORCEPROP 1 LASTPIN (2250 3475) $PN 1
J 0
(2255 3437);
DISPLAY 0.617021 (2255 3437);
PAINT ORANGE (2255 3437);
FORCEPROP 2 LAST CDS_LIB mstr_discrete
J 0
(2250 3375);
PAINT ORANGE (2250 3375);
DISPLAY INVISIBLE (2250 3375);
FORCEPROP 2 LAST SEC_TYPE 0402
J 0
(2300 3600);
DISPLAY 1.021277 (2300 3600);
PAINT ORANGE (2300 3600);
DISPLAY INVISIBLE (2300 3600);
FORCEPROP 2 LAST SEC 1
J 0
(2300 3600);
DISPLAY 0.680851 (2300 3600);
PAINT MONO (2300 3600);
DISPLAY INVISIBLE (2300 3600);
FORCEPROP 2 LAST CDS_LOCATION R8B6
J 0
(2295 3500);
DISPLAY 0.617021 (2295 3500);
PAINT AQUA (2295 3500);
DISPLAY INVISIBLE (2295 3500);
FORCEPROP 1 LAST PATH I37
J 0
(2300 3550);
DISPLAY 0.978723 (2300 3550);
PAINT WHITE (2300 3550);
DISPLAY INVISIBLE (2300 3550);
FORCEPROP 0 LAST ROOM SMBUS_CPU0_STL
J 0
(2300 3600);
DISPLAY 1.021277 (2300 3600);
PAINT ORANGE (2300 3600);
DISPLAY INVISIBLE (2300 3600);
FORCEADD GND..1
(375 2350);
FORCEPROP 3 LASTPIN (375 2400) SIG_NAME GND\g
J 0
(385 2410);
DISPLAY 0.659574 (385 2410);
PAINT MONO (385 2410);
DISPLAY INVISIBLE (385 2410);
FORCEPROP 1 LAST VOLTAGE 0.0V
J 0
(330 2307);
DISPLAY 0.340426 (330 2307);
PAINT SKYBLUE (330 2307);
DISPLAY INVISIBLE (330 2307);
FORCEPROP 1 LAST SIZE 1B
J 0
(450 2300);
DISPLAY 1.170213 (450 2300);
PAINT AQUA (450 2300);
DISPLAY INVISIBLE (450 2300);
FORCEPROP 2 LAST CDS_LIB mstr_symbols
J 0
(375 2350);
PAINT MONO (375 2350);
DISPLAY INVISIBLE (375 2350);
FORCEPROP 1 LAST PATH I38
J 0
(450 2350);
DISPLAY 0.872340 (450 2350);
PAINT AQUA (450 2350);
DISPLAY INVISIBLE (450 2350);
FORCEPROP 1 LAST BODY_TYPE PLUMBING
J 0
(330 2307);
DISPLAY 0.340426 (330 2307);
PAINT GREEN (330 2307);
DISPLAY INVISIBLE (330 2307);
FORCEPROP 1 LAST HDL_POWER GND
J 0
(375 2500);
DISPLAY 1.170213 (375 2500);
PAINT GREEN (375 2500);
DISPLAY INVISIBLE (375 2500);
FORCEADD OFFPAGE..4
(3100 3150);
FORCEPROP 2 LAST $XR0 29 
J 0
(3286 3150);
DISPLAY 0.638298 (3286 3150);
PAINT MONO (3286 3150);
FORCEPROP 2 LAST CDS_LIB mstr_standard
J 0
(3100 3150);
DISPLAY 1.340426 (3100 3150);
PAINT MONO (3100 3150);
DISPLAY INVISIBLE (3100 3150);
FORCEPROP 2 LAST PATH I4
J 0
(3425 3200);
DISPLAY 1.021277 (3425 3200);
PAINT ORANGE (3425 3200);
DISPLAY INVISIBLE (3425 3200);
FORCEPROP 1 LAST OFFPAGE TRUE
J 0
(3425 3025);
DISPLAY 1.170213 (3425 3025);
PAINT GREEN (3425 3025);
DISPLAY INVISIBLE (3425 3025);
FORCEPROP 1 LAST COMMENT_BODY TRUE
J 0
(3075 3050);
DISPLAY 1.170213 (3075 3050);
PAINT GREEN (3075 3050);
DISPLAY INVISIBLE (3075 3050);
FORCEADD OFFPAGE..3
(3100 3100);
FORCEPROP 2 LAST $XR0 29 
J 0
(3314 3100);
DISPLAY 0.638298 (3314 3100);
PAINT MONO (3314 3100);
FORCEPROP 2 LAST CDS_LIB mstr_standard
J 0
(3100 3100);
DISPLAY 1.340426 (3100 3100);
PAINT MONO (3100 3100);
DISPLAY INVISIBLE (3100 3100);
FORCEPROP 2 LAST PATH I5
J 0
(3475 3150);
DISPLAY 1.021277 (3475 3150);
PAINT ORANGE (3475 3150);
DISPLAY INVISIBLE (3475 3150);
FORCEPROP 1 LAST OFFPAGE TRUE
J 0
(3425 2975);
DISPLAY 1.170213 (3425 2975);
PAINT GREEN (3425 2975);
DISPLAY INVISIBLE (3425 2975);
FORCEPROP 1 LAST COMMENT_BODY TRUE
J 0
(3050 3000);
DISPLAY 1.170213 (3050 3000);
PAINT GREEN (3050 3000);
DISPLAY INVISIBLE (3050 3000);
FORCEADD OFFPAGE..2
(3100 3000);
FORCEPROP 2 LAST $XR0 29 
J 0
(3289 3000);
DISPLAY 0.638298 (3289 3000);
PAINT MONO (3289 3000);
FORCEPROP 2 LAST CDS_LIB mstr_standard
J 0
(3100 3000);
DISPLAY 1.340426 (3100 3000);
PAINT MONO (3100 3000);
DISPLAY INVISIBLE (3100 3000);
FORCEPROP 2 LAST PATH I6
J 0
(3300 3050);
DISPLAY 1.021277 (3300 3050);
PAINT ORANGE (3300 3050);
DISPLAY INVISIBLE (3300 3050);
FORCEPROP 1 LAST OFFPAGE TRUE
J 0
(3425 2875);
DISPLAY 0.829787 (3425 2875);
PAINT GREEN (3425 2875);
DISPLAY INVISIBLE (3425 2875);
FORCEPROP 1 LAST COMMENT_BODY TRUE
J 0
(3055 2905);
DISPLAY 1.170213 (3055 2905);
PAINT PEACH (3055 2905);
DISPLAY INVISIBLE (3055 2905);
FORCEADD OFFPAGE..2
(3100 2800);
FORCEPROP 2 LAST $XR0 29 
J 0
(3289 2800);
DISPLAY 0.638298 (3289 2800);
PAINT MONO (3289 2800);
FORCEPROP 2 LAST PATH I7
J 0
(3300 2850);
DISPLAY 1.021277 (3300 2850);
PAINT ORANGE (3300 2850);
DISPLAY INVISIBLE (3300 2850);
FORCEPROP 2 LAST CDS_LIB mstr_standard
J 0
(3100 2800);
DISPLAY 1.340426 (3100 2800);
PAINT MONO (3100 2800);
DISPLAY INVISIBLE (3100 2800);
FORCEPROP 1 LAST OFFPAGE TRUE
J 0
(3425 2675);
DISPLAY 0.829787 (3425 2675);
PAINT GREEN (3425 2675);
DISPLAY INVISIBLE (3425 2675);
FORCEPROP 1 LAST COMMENT_BODY TRUE
J 0
(3055 2705);
DISPLAY 1.170213 (3055 2705);
PAINT PEACH (3055 2705);
DISPLAY INVISIBLE (3055 2705);
FORCEADD OFFPAGE..4
(3100 2850);
FORCEPROP 2 LAST $XR0 29 
J 0
(3286 2850);
DISPLAY 0.638298 (3286 2850);
PAINT MONO (3286 2850);
FORCEPROP 2 LAST CDS_LIB mstr_standard
J 0
(3100 2850);
DISPLAY 1.340426 (3100 2850);
PAINT MONO (3100 2850);
DISPLAY INVISIBLE (3100 2850);
FORCEPROP 2 LAST PATH I8
J 0
(3325 2900);
DISPLAY 1.021277 (3325 2900);
PAINT ORANGE (3325 2900);
DISPLAY INVISIBLE (3325 2900);
FORCEPROP 1 LAST OFFPAGE TRUE
J 0
(3425 2725);
DISPLAY 0.829787 (3425 2725);
PAINT GREEN (3425 2725);
DISPLAY INVISIBLE (3425 2725);
FORCEPROP 1 LAST COMMENT_BODY TRUE
J 0
(3075 2750);
DISPLAY 1.170213 (3075 2750);
PAINT PEACH (3075 2750);
DISPLAY INVISIBLE (3075 2750);
FORCEADD OFFPAGE..3
(3100 2900);
FORCEPROP 2 LAST $XR0 29 
J 0
(3314 2900);
DISPLAY 0.638298 (3314 2900);
PAINT MONO (3314 2900);
FORCEPROP 2 LAST CDS_LIB mstr_standard
J 0
(3100 2900);
DISPLAY 1.340426 (3100 2900);
PAINT MONO (3100 2900);
DISPLAY INVISIBLE (3100 2900);
FORCEPROP 2 LAST PATH I9
J 0
(3475 2950);
DISPLAY 1.021277 (3475 2950);
PAINT ORANGE (3475 2950);
DISPLAY INVISIBLE (3475 2950);
FORCEPROP 1 LAST OFFPAGE TRUE
J 0
(3425 2775);
DISPLAY 1.170213 (3425 2775);
PAINT GREEN (3425 2775);
DISPLAY INVISIBLE (3425 2775);
FORCEPROP 1 LAST COMMENT_BODY TRUE
J 0
(3050 2800);
DISPLAY 1.170213 (3050 2800);
PAINT GREEN (3050 2800);
DISPLAY INVISIBLE (3050 2800);
FORCEADD DESIGN_NOTE..1
(950 2500);
FORCEPROP 2 LAST CDS_LIB mstr_symbols
J 0
(950 2500);
PAINT ORANGE (950 2500);
DISPLAY INVISIBLE (950 2500);
FORCEPROP 1 LAST COMMENT_BODY TRUE
J 0
(975 2600);
DISPLAY 0.978723 (975 2600);
PAINT ORANGE (975 2600);
DISPLAY INVISIBLE (975 2600);
FORCEADD INTEL_CORP_BPAGE..1
(4250 200);
FORCEPROP 1 LAST CDS_CON_LAST_MODIFIED Fri Jun 16 17:48:34 2017
J 0
(2825 525);
PAINT ORANGE (2825 525);
DISPLAY INVISIBLE (2825 525);
FORCEPROP 1 LAST CUSTOM_TXT_CDS <CURRENT_DESIGN_SHEET> OF <TOTAL_DESIGN_SHEETS>
J 0
(3750 225);
PAINT ORANGE (3750 225);
FORCEPROP 1 LAST CUSTOM_TXT_CDS <CON_LAST_MODIFIED>
J 0
(250 300);
PAINT ORANGE (250 300);
FORCEPROP 2 LAST CUSTOM_TXT_CDS <XR_PAGE_TITLE>
J 0
(-3640 5450);
DISPLAY 0.638298 (-3640 5450);
PAINT PINK (-3640 5450);
DISPLAY INVISIBLE (-3640 5450);
FORCEPROP 1 LAST SCH_TITLE HFI-IO CONNECTOR
J 0
(-3700 250);
DISPLAY 1.212766 (-3700 250);
PAINT ORANGE (-3700 250);
FORCEPROP 2 LAST PAGE_BORDER TRUE
J 0
(-3640 5450);
DISPLAY 0.638298 (-3640 5450);
PAINT PINK (-3640 5450);
DISPLAY INVISIBLE (-3640 5450);
FORCEPROP 2 LAST CDS_LIB mstr_symbols
J 0
(4250 200);
PAINT MONO (4250 200);
DISPLAY INVISIBLE (4250 200);
FORCEPROP 1 LAST COMMENT_BODY TRUE
J 0
(4262 212);
DISPLAY 0.468085 (4262 212);
PAINT GREEN (4262 212);
DISPLAY INVISIBLE (4262 212);
FORCEPROP 2 LAST CDS_XR_PAGE_TITLE CR-91 : @BASEBOARD_FAB2_LIB.BASEBOARD_FAB2(SCH_1):PAGE91
J 0
(-3640 5450);
DISPLAY 0.638298 (-3640 5450);
PAINT PINK (-3640 5450);
DISPLAY INVISIBLE (-3640 5450);
WIRE 16 -1 (-625 2400)(-625 2500);
WIRE 16 -1 (-625 2500)(-625 2600);
WIRE 16 -1 (-525 2500)(-625 2500);
WIRE 16 -1 (-625 2600)(-625 2800);
WIRE 16 -1 (-525 2600)(-625 2600);
WIRE 16 -1 (-625 2800)(-625 2950);
WIRE 16 -1 (-525 2800)(-625 2800);
WIRE 16 -1 (-625 2950)(-625 3000);
WIRE 16 -1 (-625 2950)(-525 2950);
WIRE 16 -1 (-625 3000)(-625 3150);
WIRE 16 -1 (-525 3000)(-625 3000);
WIRE 16 -1 (-625 3150)(-525 3150);
WIRE 16 -1 (-1875 3600)(-1875 3550);
WIRE 16 -1 (-1875 3550)(-1500 3550);
WIRE 16 -1 (-1875 3450)(-1875 3550);
WIRE 16 -1 (-1500 3550)(-1125 3550);
WIRE 16 -1 (-1500 3450)(-1500 3550);
WIRE 16 -1 (-1125 3550)(-750 3550);
WIRE 16 -1 (-1125 3450)(-1125 3550);
WIRE 16 -1 (-750 3550)(-750 3450);
WIRE 16 -1 (-675 2650)(-675 3600);
WIRE 16 -1 (-525 2650)(-675 2650);
WIRE 16 -1 (2250 3650)(2250 3575);
WIRE 16 -1 (1975 3575)(2250 3575);
WIRE 16 -1 (2250 3575)(2250 3475);
WIRE 16 -1 (1725 3575)(1975 3575);
WIRE 16 -1 (1975 3475)(1975 3575);
WIRE 16 -1 (1500 3575)(1725 3575);
WIRE 16 -1 (1725 3475)(1725 3575);
WIRE 16 -1 (1250 3575)(1500 3575);
WIRE 16 -1 (1500 3475)(1500 3575);
WIRE 16 -1 (1250 3575)(1000 3575);
WIRE 16 -1 (1250 3475)(1250 3575);
WIRE 16 -1 (1000 3575)(750 3575);
WIRE 16 -1 (1000 3475)(1000 3575);
WIRE 16 -1 (500 3575)(750 3575);
WIRE 16 -1 (750 3475)(750 3575);
WIRE 16 -1 (500 3475)(500 3575);
WIRE 16 -1 (425 3600)(425 2750);
WIRE 16 -1 (425 2700)(425 2750);
WIRE 16 -1 (425 2750)(275 2750);
WIRE 16 -1 (275 2700)(425 2700);
WIRE 16 -1 (375 2400)(375 2500);
WIRE 16 -1 (375 2500)(275 2500);
WIRE 16 -1 (3050 2600)(275 2600);
FORCEPROP 0 LAST SIG_NAME SMB_OCP_FRU_STBY_LVC3_SDA
J 0
(2275 2610);
DISPLAY 0.617021 (2275 2610);
PAINT ORANGE (2275 2610);
WIRE 16 -1 (275 2800)(500 2800);
WIRE 16 -1 (500 3275)(500 2800);
WIRE 16 -1 (3050 2800)(500 2800);
FORCEPROP 0 LAST SIG_NAME IRQ_HFI1_CPU0_LVT2_N
J 0
(2275 2810);
DISPLAY 0.617021 (2275 2810);
PAINT ORANGE (2275 2810);
WIRE 16 -1 (-2900 3050)(-1500 3050);
FORCEPROP 0 LAST SIG_NAME LED_HFI0_CPU0_N
J 0
(-2875 3060);
DISPLAY 0.617021 (-2875 3060);
PAINT ORANGE (-2875 3060);
WIRE 16 -1 (-1500 3250)(-1500 3050);
WIRE 16 -1 (-525 3050)(-1500 3050);
WIRE 16 -1 (-525 2750)(-2900 2750);
FORCEPROP 0 LAST SIG_NAME TP_HFI_IO_CONN0_RSVD_17
J 0
(-2875 2760);
DISPLAY 0.617021 (-2875 2760);
PAINT ORANGE (-2875 2760);
FORCEPROP 2 LASTPROP $XRERR UNIQUE?
J 0
(-3140 2750);
DISPLAY 0.638298 (-3140 2750);
PAINT MONO (-3140 2750);
DISPLAY INVISIBLE (-3140 2750);
WIRE 16 -1 (-2900 2900)(-1125 2900);
FORCEPROP 2 LAST SIG_NAME FM_MODPRST_HFI1_CPU0_LVT2_N
J 0
(-2875 2910);
DISPLAY 0.617021 (-2875 2910);
PAINT ORANGE (-2875 2910);
WIRE 16 -1 (-1125 3250)(-1125 2900);
WIRE 16 -1 (-525 2900)(-1125 2900);
WIRE 16 -1 (-525 2700)(-2900 2700);
FORCEPROP 0 LAST SIG_NAME PWRGD_PVPP_ABC
J 0
(-2875 2710);
DISPLAY 0.617021 (-2875 2710);
PAINT ORANGE (-2875 2710);
WIRE 16 -1 (3050 2650)(275 2650);
FORCEPROP 0 LAST SIG_NAME SMB_OCP_FRU_STBY_LVC3_SCL
J 0
(2275 2660);
DISPLAY 0.617021 (2275 2660);
PAINT ORANGE (2275 2660);
WIRE 16 -1 (1250 3275)(1250 3050);
WIRE 16 -1 (3050 3050)(1250 3050);
FORCEPROP 2 LAST SIG_NAME RST_HFI0_CPU0_LVT2_N
J 0
(2275 3060);
DISPLAY 0.617021 (2275 3060);
PAINT ORANGE (2275 3060);
WIRE 16 -1 (275 3050)(1250 3050);
WIRE 16 -1 (1500 3275)(1500 2900);
WIRE 16 -1 (1500 2900)(3050 2900);
FORCEPROP 0 LAST SIG_NAME SMB_HFI1_CPU0_LVC2_SDA
J 0
(2275 2910);
DISPLAY 0.617021 (2275 2910);
PAINT ORANGE (2275 2910);
WIRE 16 -1 (275 2900)(1500 2900);
WIRE 16 -1 (1725 3275)(1725 2950);
WIRE 16 -1 (1725 2950)(3050 2950);
FORCEPROP 0 LAST SIG_NAME SMB_HFI1_CPU0_LVC2_SCL
J 0
(2275 2960);
DISPLAY 0.617021 (2275 2960);
PAINT ORANGE (2275 2960);
WIRE 16 -1 (275 2950)(1725 2950);
WIRE 16 -1 (1000 3275)(1000 3000);
WIRE 16 -1 (3050 3000)(1000 3000);
FORCEPROP 0 LAST SIG_NAME IRQ_HFI0_CPU0_LVT2_N
J 0
(2275 3010);
DISPLAY 0.617021 (2275 3010);
PAINT ORANGE (2275 3010);
WIRE 16 -1 (275 3000)(1000 3000);
WIRE 16 -1 (275 2850)(750 2850);
WIRE 16 -1 (3050 2850)(750 2850);
FORCEPROP 0 LAST SIG_NAME RST_HFI1_CPU0_LVT2_N
J 0
(2276 2856);
DISPLAY 0.617021 (2276 2856);
PAINT ORANGE (2276 2856);
WIRE 16 -1 (750 3275)(750 2850);
WIRE 16 -1 (1975 3275)(1975 3100);
WIRE 16 -1 (1975 3100)(3050 3100);
WIRE 16 -1 (275 3100)(1975 3100);
FORCEPROP 0 LAST SIG_NAME SMB_HFI0_CPU0_LVC2_SDA
J 0
(2275 3110);
DISPLAY 0.617021 (2275 3110);
PAINT ORANGE (2275 3110);
WIRE 16 -1 (2250 3275)(2250 3150);
WIRE 16 -1 (2250 3150)(3050 3150);
WIRE 16 -1 (275 3150)(2250 3150);
FORCEPROP 0 LAST SIG_NAME SMB_HFI0_CPU0_LVC2_SCL
J 0
(2275 3160);
DISPLAY 0.617021 (2275 3160);
PAINT ORANGE (2275 3160);
WIRE 16 -1 (-2900 2850)(-750 2850);
FORCEPROP 0 LAST SIG_NAME LED_HFI1_CPU0_N
J 0
(-2875 2860);
DISPLAY 0.617021 (-2875 2860);
PAINT ORANGE (-2875 2860);
WIRE 16 -1 (-525 2850)(-750 2850);
WIRE 16 -1 (-750 3250)(-750 2850);
WIRE 16 -1 (-2900 3100)(-1875 3100);
FORCEPROP 0 LAST SIG_NAME FM_MODPRST_HFI0_CPU0_LVT2_N
J 0
(-2875 3110);
DISPLAY 0.617021 (-2875 3110);
PAINT ORANGE (-2875 3110);
WIRE 16 -1 (-1875 3250)(-1875 3100);
WIRE 16 -1 (-525 3100)(-1875 3100);
DOT 1 (1725 2950);
DOT 1 (2250 3575);
DOT 1 (2250 3150);
DOT 1 (1975 3575);
DOT 1 (1975 3100);
DOT 1 (1725 3575);
DOT 1 (1500 3575);
DOT 1 (1250 3575);
DOT 1 (1000 3575);
DOT 1 (1500 2900);
DOT 1 (1250 3050);
DOT 1 (1000 3000);
DOT 1 (750 3575);
DOT 1 (750 2850);
DOT 1 (500 2800);
DOT 1 (425 2750);
DOT 1 (-1125 3550);
DOT 1 (-625 3000);
DOT 1 (-625 2950);
DOT 1 (-625 2800);
DOT 1 (-625 2600);
DOT 1 (-625 2500);
DOT 1 (-750 2850);
DOT 1 (-1125 2900);
DOT 1 (-1500 3550);
DOT 1 (-1875 3550);
DOT 1 (-1875 3100);
DOT 1 (-1500 3050);
FORCENOTE
OCP MEZZ A AND MCP SIDEBAND HFI:
(750 2400) 0;
DISPLAY LEFT (750 2400);
DISPLAY 1.021277 (750 2400);
PAINT PURPLE (750 2400);
FORCENOTE
FRU SMBUS ADDRESS 0XA2
(800 2350) 0;
DISPLAY LEFT (800 2350);
DISPLAY 1.021277 (800 2350);
PAINT PURPLE (800 2350);
FORCENOTE
TEMP SMBUS ADDRESS 0X3E
(800 2300) 0;
DISPLAY LEFT (800 2300);
DISPLAY 1.021277 (800 2300);
PAINT PURPLE (800 2300);
FORCENOTE
OCP MEZZ C:
(750 2250) 0;
DISPLAY LEFT (750 2250);
DISPLAY 1.021277 (750 2250);
PAINT PURPLE (750 2250);
FORCENOTE
FRU SMBUS ADDRESS 0XAE
(800 2200) 0;
DISPLAY LEFT (800 2200);
DISPLAY 1.021277 (800 2200);
PAINT PURPLE (800 2200);
FORCENOTE
TEMP SMBUS ADDRESS 0X3E
(800 2150) 0;
DISPLAY LEFT (800 2150);
DISPLAY 1.021277 (800 2150);
PAINT PURPLE (800 2150);
FORCENOTE
FOR DEBUG ONLY
(-550 2250) 0;
DISPLAY LEFT (-550 2250);
DISPLAY 1.021277 (-550 2250);
PAINT PURPLE (-550 2250);
FORCENOTE
ROOM=HFI
(-3650 550) 0;
DISPLAY LEFT (-3650 550);
DISPLAY 1.021277 (-3650 550);
PAINT PURPLE (-3650 550);
FORCENOTE
BOM_COST=PROC_SIDEBAND
(-3625 475) 0;
DISPLAY LEFT (-3625 475);
DISPLAY 1.021277 (-3625 475);
PAINT PURPLE (-3625 475);
QUIT
